(kicad_pcb
	(version 20260206)
	(generator "pcbnew")
	(generator_version "10.0")
	(general
		(thickness 1.6)
		(legacy_teardrops no)
	)
	(paper "A4")
	(title_block
		(title "03242023_DA0F0TMBIJ0_F0T_Motherboard_J_brd_V01_OCP.brd")
		(comment 1 "Grand Teton / footprints 5645-5651 of 6105")
	)
	(layers
		(0 "F.Cu" signal "TOP")
		(4 "In1.Cu" signal "GND")
		(6 "In2.Cu" signal "IN1")
		(8 "In3.Cu" signal "GND1")
		(10 "In4.Cu" signal "IN2")
		(12 "In5.Cu" signal "GND2")
		(14 "In6.Cu" signal "IN3")
		(16 "In7.Cu" signal "GND3")
		(18 "In8.Cu" signal "VCC")
		(20 "In9.Cu" signal "VCC1")
		(22 "In10.Cu" signal "GND4")
		(24 "In11.Cu" signal "IN4")
		(26 "In12.Cu" signal "GND5")
		(28 "In13.Cu" signal "IN5")
		(30 "In14.Cu" signal "GND6")
		(32 "In15.Cu" signal "IN6")
		(34 "In16.Cu" signal "GND7")
		(2 "B.Cu" signal "BOTTOM")
		(9 "F.Adhes" user "F.Adhesive")
		(11 "B.Adhes" user "B.Adhesive")
		(13 "F.Paste" user "Package Geometry/Pastemask Top")
		(15 "B.Paste" user "Package Geometry/Pastemask Bottom")
		(5 "F.SilkS" user "Ref Des/Silkscreen Top")
		(7 "B.SilkS" user "Ref Des/Silkscreen Bottom")
		(1 "F.Mask" user "Board Geometry/Soldermask Top")
		(3 "B.Mask" user "Board Geometry/Soldermask Bottom")
		(17 "Dwgs.User" user "User.Drawings")
		(19 "Cmts.User" user "User.Comments")
		(21 "Eco1.User" user "User.Eco1")
		(23 "Eco2.User" user "User.Eco2")
		(25 "Edge.Cuts" user "Board Geometry/Outline")
		(27 "Margin" user)
		(31 "F.CrtYd" user "Package Geometry/Place Bound Top")
		(29 "B.CrtYd" user "Package Geometry/Place Bound Bottom")
		(35 "F.Fab" user "Ref Des/Assembly Top")
		(33 "B.Fab" user "Ref Des/Assembly Bottom")
	)
	(footprint ""
		(layer "B.Cu")
		(at 97.46996 -422.143428 -90)
		(property "Reference" "C2340"
			(at 0 0 90)
			(layer "B.SilkS")
			(hide yes)
			(effects
				(font
					(size 1.27 1.27)
				)
				(justify mirror)
			)
		)
		(property "Value" ""
			(at 0 0 90)
			(layer "B.Fab")
			(effects
				(font
					(size 1.27 1.27)
				)
				(justify mirror)
			)
		)
		(duplicate_pad_numbers_are_jumpers no)
		(fp_line
			(start -0.7874 0.4064)
			(end 0.7874 0.4064)
			(stroke
				(width 0.1524)
				(type default)
			)
			(layer "B.SilkS")
		)
		(fp_line
			(start 0.7874 0.4064)
			(end 0.7874 -0.4064)
			(stroke
				(width 0.1524)
				(type default)
			)
			(layer "B.SilkS")
		)
		(fp_line
			(start -0.7874 -0.4064)
			(end -0.7874 0.4064)
			(stroke
				(width 0.1524)
				(type default)
			)
			(layer "B.SilkS")
		)
		(fp_line
			(start 0.7874 -0.4064)
			(end -0.7874 -0.4064)
			(stroke
				(width 0.1524)
				(type default)
			)
			(layer "B.SilkS")
		)
		(fp_line
			(start -0.67945 0.3048)
			(end -0.120396 0.3048)
			(stroke
				(width 0.1)
				(type default)
			)
			(layer "B.Fab")
		)
		(fp_line
			(start -0.120396 0.3048)
			(end -0.120396 0.2794)
			(stroke
				(width 0.1)
				(type default)
			)
			(layer "B.Fab")
		)
		(fp_line
			(start 0.12065 0.3048)
			(end 0.67945 0.3048)
			(stroke
				(width 0.1)
				(type default)
			)
			(layer "B.Fab")
		)
		(fp_line
			(start 0.67945 0.3048)
			(end 0.67945 -0.305054)
			(stroke
				(width 0.1)
				(type default)
			)
			(layer "B.Fab")
		)
		(fp_line
			(start -0.120396 0.2794)
			(end 0.12065 0.2794)
			(stroke
				(width 0.1)
				(type default)
			)
			(layer "B.Fab")
		)
		(fp_line
			(start 0.12065 0.2794)
			(end 0.12065 0.3048)
			(stroke
				(width 0.1)
				(type default)
			)
			(layer "B.Fab")
		)
		(fp_line
			(start -0.12065 -0.2794)
			(end -0.12065 -0.3048)
			(stroke
				(width 0.1)
				(type default)
			)
			(layer "B.Fab")
		)
		(fp_line
			(start 0.12065 -0.2794)
			(end -0.12065 -0.2794)
			(stroke
				(width 0.1)
				(type default)
			)
			(layer "B.Fab")
		)
		(fp_line
			(start -0.67945 -0.3048)
			(end -0.67945 0.3048)
			(stroke
				(width 0.1)
				(type default)
			)
			(layer "B.Fab")
		)
		(fp_line
			(start -0.12065 -0.3048)
			(end -0.67945 -0.3048)
			(stroke
				(width 0.1)
				(type default)
			)
			(layer "B.Fab")
		)
		(fp_line
			(start 0.12065 -0.305054)
			(end 0.12065 -0.2794)
			(stroke
				(width 0.1)
				(type default)
			)
			(layer "B.Fab")
		)
		(fp_line
			(start 0.67945 -0.305054)
			(end 0.12065 -0.305054)
			(stroke
				(width 0.1)
				(type default)
			)
			(layer "B.Fab")
		)
		(pad "1" smd circle
			(at 0.40005 0 90)
			(size 0 0)
			(layers "B.Cu" "B.Mask" "B.Paste")
			(net "HGX_DETECT_N_ISO")
		)
		(pad "2" smd circle
			(at -0.40005 0 90)
			(size 0 0)
			(layers "B.Cu" "B.Mask" "B.Paste")
			(net "GND")
		)
	)
	(footprint ""
		(layer "B.Cu")
		(at 101.717348 -336.192368 -90)
		(property "Reference" "PR329"
			(at 0 0 90)
			(layer "B.SilkS")
			(hide yes)
			(effects
				(font
					(size 1.27 1.27)
				)
				(justify mirror)
			)
		)
		(property "Value" ""
			(at 0 0 90)
			(layer "B.Fab")
			(effects
				(font
					(size 1.27 1.27)
				)
				(justify mirror)
			)
		)
		(duplicate_pad_numbers_are_jumpers no)
		(fp_line
			(start -0.7874 0.4064)
			(end 0.7874 0.4064)
			(stroke
				(width 0.1524)
				(type default)
			)
			(layer "B.SilkS")
		)
		(fp_line
			(start 0.7874 0.4064)
			(end 0.7874 -0.4064)
			(stroke
				(width 0.1524)
				(type default)
			)
			(layer "B.SilkS")
		)
		(fp_line
			(start -0.7874 -0.4064)
			(end -0.7874 0.4064)
			(stroke
				(width 0.1524)
				(type default)
			)
			(layer "B.SilkS")
		)
		(fp_line
			(start 0.7874 -0.4064)
			(end -0.7874 -0.4064)
			(stroke
				(width 0.1524)
				(type default)
			)
			(layer "B.SilkS")
		)
		(fp_line
			(start -0.67945 0.3048)
			(end -0.120396 0.3048)
			(stroke
				(width 0.1)
				(type default)
			)
			(layer "B.Fab")
		)
		(fp_line
			(start -0.120396 0.3048)
			(end -0.120396 0.2794)
			(stroke
				(width 0.1)
				(type default)
			)
			(layer "B.Fab")
		)
		(fp_line
			(start 0.12065 0.3048)
			(end 0.67945 0.3048)
			(stroke
				(width 0.1)
				(type default)
			)
			(layer "B.Fab")
		)
		(fp_line
			(start 0.67945 0.3048)
			(end 0.67945 -0.305054)
			(stroke
				(width 0.1)
				(type default)
			)
			(layer "B.Fab")
		)
		(fp_line
			(start -0.120396 0.2794)
			(end 0.12065 0.2794)
			(stroke
				(width 0.1)
				(type default)
			)
			(layer "B.Fab")
		)
		(fp_line
			(start 0.12065 0.2794)
			(end 0.12065 0.3048)
			(stroke
				(width 0.1)
				(type default)
			)
			(layer "B.Fab")
		)
		(fp_line
			(start -0.12065 -0.2794)
			(end -0.12065 -0.3048)
			(stroke
				(width 0.1)
				(type default)
			)
			(layer "B.Fab")
		)
		(fp_line
			(start 0.12065 -0.2794)
			(end -0.12065 -0.2794)
			(stroke
				(width 0.1)
				(type default)
			)
			(layer "B.Fab")
		)
		(fp_line
			(start -0.67945 -0.3048)
			(end -0.67945 0.3048)
			(stroke
				(width 0.1)
				(type default)
			)
			(layer "B.Fab")
		)
		(fp_line
			(start -0.12065 -0.3048)
			(end -0.67945 -0.3048)
			(stroke
				(width 0.1)
				(type default)
			)
			(layer "B.Fab")
		)
		(fp_line
			(start 0.12065 -0.305054)
			(end 0.12065 -0.2794)
			(stroke
				(width 0.1)
				(type default)
			)
			(layer "B.Fab")
		)
		(fp_line
			(start 0.67945 -0.305054)
			(end 0.12065 -0.305054)
			(stroke
				(width 0.1)
				(type default)
			)
			(layer "B.Fab")
		)
		(pad "1" smd circle
			(at 0.40005 0 90)
			(size 0 0)
			(layers "B.Cu" "B.Mask" "B.Paste")
			(net "PVCCIN_CPU1_VOS2")
		)
		(pad "2" smd circle
			(at -0.40005 0 90)
			(size 0 0)
			(layers "B.Cu" "B.Mask" "B.Paste")
			(net "PVCCIN_CPU1")
		)
	)
	(footprint ""
		(layer "B.Cu")
		(at 367.898934 -259.531866 90)
		(property "Reference" "C522"
			(at 0 0 90)
			(layer "B.SilkS")
			(hide yes)
			(effects
				(font
					(size 1.27 1.27)
				)
				(justify mirror)
			)
		)
		(property "Value" ""
			(at 0 0 90)
			(layer "B.Fab")
			(effects
				(font
					(size 1.27 1.27)
				)
				(justify mirror)
			)
		)
		(duplicate_pad_numbers_are_jumpers no)
		(fp_line
			(start 1.524 -0.762)
			(end -1.524 -0.762)
			(stroke
				(width 0.1524)
				(type default)
			)
			(layer "B.SilkS")
		)
		(fp_line
			(start -1.524 -0.762)
			(end -1.524 0.762)
			(stroke
				(width 0.1524)
				(type default)
			)
			(layer "B.SilkS")
		)
		(fp_line
			(start 1.524 0.762)
			(end 1.524 -0.762)
			(stroke
				(width 0.1524)
				(type default)
			)
			(layer "B.SilkS")
		)
		(fp_line
			(start -1.524 0.762)
			(end 1.524 0.762)
			(stroke
				(width 0.1524)
				(type default)
			)
			(layer "B.SilkS")
		)
		(fp_line
			(start 1.1049 -0.724916)
			(end 1.1049 0.724916)
			(stroke
				(width 0.1)
				(type default)
			)
			(layer "B.Fab")
		)
		(fp_line
			(start -1.1049 -0.724916)
			(end 1.1049 -0.724916)
			(stroke
				(width 0.1)
				(type default)
			)
			(layer "B.Fab")
		)
		(fp_line
			(start 1.1049 0.724916)
			(end -1.1049 0.724916)
			(stroke
				(width 0.1)
				(type default)
			)
			(layer "B.Fab")
		)
		(fp_line
			(start -1.1049 0.724916)
			(end -1.1049 -0.724916)
			(stroke
				(width 0.1)
				(type default)
			)
			(layer "B.Fab")
		)
		(pad "1" smd rect
			(at 0.889 0 90)
			(size 1.016 1.27)
			(layers "B.Cu" "B.Mask" "B.Paste")
			(net "PVCCINFAON_CPU0")
		)
		(pad "2" smd rect
			(at -0.889 0 90)
			(size 1.016 1.27)
			(layers "B.Cu" "B.Mask" "B.Paste")
			(net "GND")
		)
	)
	(footprint ""
		(layer "B.Cu")
		(at 180.923692 -408.254708 90)
		(property "Reference" "R1714"
			(at 0 0 90)
			(layer "B.SilkS")
			(hide yes)
			(effects
				(font
					(size 1.27 1.27)
				)
				(justify mirror)
			)
		)
		(property "Value" ""
			(at 0 0 90)
			(layer "B.Fab")
			(effects
				(font
					(size 1.27 1.27)
				)
				(justify mirror)
			)
		)
		(duplicate_pad_numbers_are_jumpers no)
		(fp_line
			(start 0.7874 -0.4064)
			(end -0.7874 -0.4064)
			(stroke
				(width 0.1524)
				(type default)
			)
			(layer "B.SilkS")
		)
		(fp_line
			(start -0.7874 -0.4064)
			(end -0.7874 0.4064)
			(stroke
				(width 0.1524)
				(type default)
			)
			(layer "B.SilkS")
		)
		(fp_line
			(start 0.7874 0.4064)
			(end 0.7874 -0.4064)
			(stroke
				(width 0.1524)
				(type default)
			)
			(layer "B.SilkS")
		)
		(fp_line
			(start -0.7874 0.4064)
			(end 0.7874 0.4064)
			(stroke
				(width 0.1524)
				(type default)
			)
			(layer "B.SilkS")
		)
		(fp_line
			(start 0.67945 -0.305054)
			(end 0.12065 -0.305054)
			(stroke
				(width 0.1)
				(type default)
			)
			(layer "B.Fab")
		)
		(fp_line
			(start 0.12065 -0.305054)
			(end 0.12065 -0.2794)
			(stroke
				(width 0.1)
				(type default)
			)
			(layer "B.Fab")
		)
		(fp_line
			(start -0.12065 -0.3048)
			(end -0.67945 -0.3048)
			(stroke
				(width 0.1)
				(type default)
			)
			(layer "B.Fab")
		)
		(fp_line
			(start -0.67945 -0.3048)
			(end -0.67945 0.3048)
			(stroke
				(width 0.1)
				(type default)
			)
			(layer "B.Fab")
		)
		(fp_line
			(start 0.12065 -0.2794)
			(end -0.12065 -0.2794)
			(stroke
				(width 0.1)
				(type default)
			)
			(layer "B.Fab")
		)
		(fp_line
			(start -0.12065 -0.2794)
			(end -0.12065 -0.3048)
			(stroke
				(width 0.1)
				(type default)
			)
			(layer "B.Fab")
		)
		(fp_line
			(start 0.12065 0.2794)
			(end 0.12065 0.3048)
			(stroke
				(width 0.1)
				(type default)
			)
			(layer "B.Fab")
		)
		(fp_line
			(start -0.120396 0.2794)
			(end 0.12065 0.2794)
			(stroke
				(width 0.1)
				(type default)
			)
			(layer "B.Fab")
		)
		(fp_line
			(start 0.67945 0.3048)
			(end 0.67945 -0.305054)
			(stroke
				(width 0.1)
				(type default)
			)
			(layer "B.Fab")
		)
		(fp_line
			(start 0.12065 0.3048)
			(end 0.67945 0.3048)
			(stroke
				(width 0.1)
				(type default)
			)
			(layer "B.Fab")
		)
		(fp_line
			(start -0.120396 0.3048)
			(end -0.120396 0.2794)
			(stroke
				(width 0.1)
				(type default)
			)
			(layer "B.Fab")
		)
		(fp_line
			(start -0.67945 0.3048)
			(end -0.120396 0.3048)
			(stroke
				(width 0.1)
				(type default)
			)
			(layer "B.Fab")
		)
		(pad "1" smd circle
			(at 0.40005 0 270)
			(size 0 0)
			(layers "B.Cu" "B.Mask" "B.Paste")
			(net "SMB_SML1_PMBUS_HSC_SDA")
		)
		(pad "2" smd circle
			(at -0.40005 0 270)
			(size 0 0)
			(layers "B.Cu" "B.Mask" "B.Paste")
			(net "SMB_SML1_PMBUS_HSC_R_SDA")
		)
	)
	(footprint ""
		(layer "B.Cu")
		(at 329.134978 -28.852622 90)
		(property "Reference" "R610"
			(at 0 0 90)
			(layer "B.SilkS")
			(hide yes)
			(effects
				(font
					(size 1.27 1.27)
				)
				(justify mirror)
			)
		)
		(property "Value" ""
			(at 0 0 90)
			(layer "B.Fab")
			(effects
				(font
					(size 1.27 1.27)
				)
				(justify mirror)
			)
		)
		(duplicate_pad_numbers_are_jumpers no)
		(fp_line
			(start 0.7874 -0.4064)
			(end -0.7874 -0.4064)
			(stroke
				(width 0.1524)
				(type default)
			)
			(layer "B.SilkS")
		)
		(fp_line
			(start -0.7874 -0.4064)
			(end -0.7874 0.4064)
			(stroke
				(width 0.1524)
				(type default)
			)
			(layer "B.SilkS")
		)
		(fp_line
			(start 0.7874 0.4064)
			(end 0.7874 -0.4064)
			(stroke
				(width 0.1524)
				(type default)
			)
			(layer "B.SilkS")
		)
		(fp_line
			(start -0.7874 0.4064)
			(end 0.7874 0.4064)
			(stroke
				(width 0.1524)
				(type default)
			)
			(layer "B.SilkS")
		)
		(fp_line
			(start 0.67945 -0.305054)
			(end 0.12065 -0.305054)
			(stroke
				(width 0.1)
				(type default)
			)
			(layer "B.Fab")
		)
		(fp_line
			(start 0.12065 -0.305054)
			(end 0.12065 -0.2794)
			(stroke
				(width 0.1)
				(type default)
			)
			(layer "B.Fab")
		)
		(fp_line
			(start -0.12065 -0.3048)
			(end -0.67945 -0.3048)
			(stroke
				(width 0.1)
				(type default)
			)
			(layer "B.Fab")
		)
		(fp_line
			(start -0.67945 -0.3048)
			(end -0.67945 0.3048)
			(stroke
				(width 0.1)
				(type default)
			)
			(layer "B.Fab")
		)
		(fp_line
			(start 0.12065 -0.2794)
			(end -0.12065 -0.2794)
			(stroke
				(width 0.1)
				(type default)
			)
			(layer "B.Fab")
		)
		(fp_line
			(start -0.12065 -0.2794)
			(end -0.12065 -0.3048)
			(stroke
				(width 0.1)
				(type default)
			)
			(layer "B.Fab")
		)
		(fp_line
			(start 0.12065 0.2794)
			(end 0.12065 0.3048)
			(stroke
				(width 0.1)
				(type default)
			)
			(layer "B.Fab")
		)
		(fp_line
			(start -0.120396 0.2794)
			(end 0.12065 0.2794)
			(stroke
				(width 0.1)
				(type default)
			)
			(layer "B.Fab")
		)
		(fp_line
			(start 0.67945 0.3048)
			(end 0.67945 -0.305054)
			(stroke
				(width 0.1)
				(type default)
			)
			(layer "B.Fab")
		)
		(fp_line
			(start 0.12065 0.3048)
			(end 0.67945 0.3048)
			(stroke
				(width 0.1)
				(type default)
			)
			(layer "B.Fab")
		)
		(fp_line
			(start -0.120396 0.3048)
			(end -0.120396 0.2794)
			(stroke
				(width 0.1)
				(type default)
			)
			(layer "B.Fab")
		)
		(fp_line
			(start -0.67945 0.3048)
			(end -0.120396 0.3048)
			(stroke
				(width 0.1)
				(type default)
			)
			(layer "B.Fab")
		)
		(pad "1" smd circle
			(at 0.40005 0 270)
			(size 0 0)
			(layers "B.Cu" "B.Mask" "B.Paste")
			(net "FM_ESPI_CS_SWIZZLE")
		)
		(pad "2" smd circle
			(at -0.40005 0 270)
			(size 0 0)
			(layers "B.Cu" "B.Mask" "B.Paste")
			(net "GND")
		)
	)
	(footprint ""
		(layer "B.Cu")
		(at 25.072848 -318.633856)
		(property "Reference" "R46"
			(at 0 0 0)
			(layer "B.SilkS")
			(hide yes)
			(effects
				(font
					(size 1.27 1.27)
				)
				(justify mirror)
			)
		)
		(property "Value" ""
			(at 0 0 0)
			(layer "B.Fab")
			(effects
				(font
					(size 1.27 1.27)
				)
				(justify mirror)
			)
		)
		(duplicate_pad_numbers_are_jumpers no)
		(fp_line
			(start -0.7874 -0.4064)
			(end -0.7874 0.4064)
			(stroke
				(width 0.1524)
				(type default)
			)
			(layer "B.SilkS")
		)
		(fp_line
			(start -0.7874 0.4064)
			(end 0.7874 0.4064)
			(stroke
				(width 0.1524)
				(type default)
			)
			(layer "B.SilkS")
		)
		(fp_line
			(start 0.7874 -0.4064)
			(end -0.7874 -0.4064)
			(stroke
				(width 0.1524)
				(type default)
			)
			(layer "B.SilkS")
		)
		(fp_line
			(start 0.7874 0.4064)
			(end 0.7874 -0.4064)
			(stroke
				(width 0.1524)
				(type default)
			)
			(layer "B.SilkS")
		)
		(fp_line
			(start -0.67945 -0.3048)
			(end -0.67945 0.3048)
			(stroke
				(width 0.1)
				(type default)
			)
			(layer "B.Fab")
		)
		(fp_line
			(start -0.67945 0.3048)
			(end -0.120396 0.3048)
			(stroke
				(width 0.1)
				(type default)
			)
			(layer "B.Fab")
		)
		(fp_line
			(start -0.12065 -0.3048)
			(end -0.67945 -0.3048)
			(stroke
				(width 0.1)
				(type default)
			)
			(layer "B.Fab")
		)
		(fp_line
			(start -0.12065 -0.2794)
			(end -0.12065 -0.3048)
			(stroke
				(width 0.1)
				(type default)
			)
			(layer "B.Fab")
		)
		(fp_line
			(start -0.120396 0.2794)
			(end 0.12065 0.2794)
			(stroke
				(width 0.1)
				(type default)
			)
			(layer "B.Fab")
		)
		(fp_line
			(start -0.120396 0.3048)
			(end -0.120396 0.2794)
			(stroke
				(width 0.1)
				(type default)
			)
			(layer "B.Fab")
		)
		(fp_line
			(start 0.12065 -0.305054)
			(end 0.12065 -0.2794)
			(stroke
				(width 0.1)
				(type default)
			)
			(layer "B.Fab")
		)
		(fp_line
			(start 0.12065 -0.2794)
			(end -0.12065 -0.2794)
			(stroke
				(width 0.1)
				(type default)
			)
			(layer "B.Fab")
		)
		(fp_line
			(start 0.12065 0.2794)
			(end 0.12065 0.3048)
			(stroke
				(width 0.1)
				(type default)
			)
			(layer "B.Fab")
		)
		(fp_line
			(start 0.12065 0.3048)
			(end 0.67945 0.3048)
			(stroke
				(width 0.1)
				(type default)
			)
			(layer "B.Fab")
		)
		(fp_line
			(start 0.67945 -0.305054)
			(end 0.12065 -0.305054)
			(stroke
				(width 0.1)
				(type default)
			)
			(layer "B.Fab")
		)
		(fp_line
			(start 0.67945 0.3048)
			(end 0.67945 -0.305054)
			(stroke
				(width 0.1)
				(type default)
			)
			(layer "B.Fab")
		)
		(pad "1" smd circle
			(at 0.40005 0 180)
			(size 0 0)
			(layers "B.Cu" "B.Mask" "B.Paste")
			(net "PD_CHC_CPU1_DIMM1_SAA")
		)
		(pad "2" smd circle
			(at -0.40005 0 180)
			(size 0 0)
			(layers "B.Cu" "B.Mask" "B.Paste")
			(net "GND")
		)
	)
	(footprint ""
		(layer "B.Cu")
		(at 353.658678 -241.13871 90)
		(property "Reference" "C527"
			(at 0 0 90)
			(layer "B.SilkS")
			(hide yes)
			(effects
				(font
					(size 1.27 1.27)
				)
				(justify mirror)
			)
		)
		(property "Value" ""
			(at 0 0 90)
			(layer "B.Fab")
			(effects
				(font
					(size 1.27 1.27)
				)
				(justify mirror)
			)
		)
		(duplicate_pad_numbers_are_jumpers no)
		(fp_line
			(start 1.524 -0.762)
			(end -1.524 -0.762)
			(stroke
				(width 0.1524)
				(type default)
			)
			(layer "B.SilkS")
		)
		(fp_line
			(start -1.524 -0.762)
			(end -1.524 0.762)
			(stroke
				(width 0.1524)
				(type default)
			)
			(layer "B.SilkS")
		)
		(fp_line
			(start 1.524 0.762)
			(end 1.524 -0.762)
			(stroke
				(width 0.1524)
				(type default)
			)
			(layer "B.SilkS")
		)
		(fp_line
			(start -1.524 0.762)
			(end 1.524 0.762)
			(stroke
				(width 0.1524)
				(type default)
			)
			(layer "B.SilkS")
		)
		(fp_line
			(start 1.1049 -0.724916)
			(end 1.1049 0.724916)
			(stroke
				(width 0.1)
				(type default)
			)
			(layer "B.Fab")
		)
		(fp_line
			(start -1.1049 -0.724916)
			(end 1.1049 -0.724916)
			(stroke
				(width 0.1)
				(type default)
			)
			(layer "B.Fab")
		)
		(fp_line
			(start 1.1049 0.724916)
			(end -1.1049 0.724916)
			(stroke
				(width 0.1)
				(type default)
			)
			(layer "B.Fab")
		)
		(fp_line
			(start -1.1049 0.724916)
			(end -1.1049 -0.724916)
			(stroke
				(width 0.1)
				(type default)
			)
			(layer "B.Fab")
		)
		(pad "1" smd rect
			(at 0.889 0 90)
			(size 1.016 1.27)
			(layers "B.Cu" "B.Mask" "B.Paste")
			(net "PVCCIN_CPU0")
		)
		(pad "2" smd rect
			(at -0.889 0 90)
			(size 1.016 1.27)
			(layers "B.Cu" "B.Mask" "B.Paste")
			(net "GND")
		)
	)
)
